# T6G (Grand Teton) — schematic netlist excerpt (pin names and nets, part order shuffled) for the footprints in the layout excerpt that follows; sources: Cadence DE-HDL packaged netlist, KiCad conversion of 04192023_DAF0TMB3IC0_F0TG_MB_C_brd_V02_OCP.brd

C2670  Q_CAP  22UF 4V 20% X6S  pkg C0402  page 75 : A = PVDD18_S5_P1 ; B = GND
R1264  Q_RES  1K 1% EMPTY  pkg 0402LF  page 167 : A = P1V8_AUX ; B = BIOS_DEBUG_MODE

(kicad_pcb
	(version 20260206)
	(generator "pcbnew")
	(generator_version "10.0")
	(general
		(thickness 1.6)
		(legacy_teardrops no)
	)
	(paper "A4")
	(title_block
		(title "04192023_DAF0TMB3IC0_F0TG_MB_C_brd_V02_OCP.brd")
		(comment 1 "Grand Teton / footprints 6964-6965 of 8354")
	)
	(layers
		(0 "F.Cu" signal "TOP")
		(4 "In1.Cu" signal "GND")
		(6 "In2.Cu" signal "IN1")
		(8 "In3.Cu" signal "GND1")
		(10 "In4.Cu" signal "IN2")
		(12 "In5.Cu" signal "GND2")
		(14 "In6.Cu" signal "IN3")
		(16 "In7.Cu" signal "GND3")
		(18 "In8.Cu" signal "VCC")
		(20 "In9.Cu" signal "VCC1")
		(22 "In10.Cu" signal "GND4")
		(24 "In11.Cu" signal "IN4")
		(26 "In12.Cu" signal "GND5")
		(28 "In13.Cu" signal "IN5")
		(30 "In14.Cu" signal "GND6")
		(32 "In15.Cu" signal "IN6")
		(34 "In16.Cu" signal "GND7")
		(2 "B.Cu" signal "BOTTOM")
		(9 "F.Adhes" user "F.Adhesive")
		(11 "B.Adhes" user "B.Adhesive")
		(13 "F.Paste" user "Package Geometry/Pastemask Top")
		(15 "B.Paste" user "Package Geometry/Pastemask Bottom")
		(5 "F.SilkS" user "Ref Des/Silkscreen Top")
		(7 "B.SilkS" user "Ref Des/Silkscreen Bottom")
		(1 "F.Mask" user "Board Geometry/Soldermask Top")
		(3 "B.Mask" user "Board Geometry/Soldermask Bottom")
		(17 "Dwgs.User" user "User.Drawings")
		(19 "Cmts.User" user "User.Comments")
		(21 "Eco1.User" user "User.Eco1")
		(23 "Eco2.User" user "User.Eco2")
		(25 "Edge.Cuts" user "Board Geometry/Outline")
		(27 "Margin" user)
		(31 "F.CrtYd" user "Package Geometry/Place Bound Top")
		(29 "B.CrtYd" user "Package Geometry/Place Bound Bottom")
		(35 "F.Fab" user "Ref Des/Assembly Top")
		(33 "B.Fab" user "Ref Des/Assembly Bottom")
	)
	(footprint ""
		(layer "B.Cu")
		(at 99.001834 -249.368564 180)
		(property "Reference" "C2670"
			(at 0 0 0)
			(layer "B.SilkS")
			(hide yes)
			(effects
				(font
					(size 1.27 1.27)
				)
				(justify mirror)
			)
		)
		(property "Value" ""
			(at 0 0 0)
			(layer "B.Fab")
			(effects
				(font
					(size 1.27 1.27)
				)
				(justify mirror)
			)
		)
		(duplicate_pad_numbers_are_jumpers no)
		(fp_line
			(start 0.7874 0.4064)
			(end 0.7874 -0.4064)
			(stroke
				(width 0.1524)
				(type default)
			)
			(layer "B.SilkS")
		)
		(fp_line
			(start 0.7874 -0.4064)
			(end -0.7874 -0.4064)
			(stroke
				(width 0.1524)
				(type default)
			)
			(layer "B.SilkS")
		)
		(fp_line
			(start -0.7874 0.4064)
			(end 0.7874 0.4064)
			(stroke
				(width 0.1524)
				(type default)
			)
			(layer "B.SilkS")
		)
		(fp_line
			(start -0.7874 -0.4064)
			(end -0.7874 0.4064)
			(stroke
				(width 0.1524)
				(type default)
			)
			(layer "B.SilkS")
		)
		(fp_line
			(start 0.67945 0.3048)
			(end 0.67945 -0.305054)
			(stroke
				(width 0.1)
				(type default)
			)
			(layer "B.Fab")
		)
		(fp_line
			(start 0.67945 -0.305054)
			(end 0.12065 -0.305054)
			(stroke
				(width 0.1)
				(type default)
			)
			(layer "B.Fab")
		)
		(fp_line
			(start 0.12065 0.3048)
			(end 0.67945 0.3048)
			(stroke
				(width 0.1)
				(type default)
			)
			(layer "B.Fab")
		)
		(fp_line
			(start 0.12065 0.2794)
			(end 0.12065 0.3048)
			(stroke
				(width 0.1)
				(type default)
			)
			(layer "B.Fab")
		)
		(fp_line
			(start 0.12065 -0.2794)
			(end -0.12065 -0.2794)
			(stroke
				(width 0.1)
				(type default)
			)
			(layer "B.Fab")
		)
		(fp_line
			(start 0.12065 -0.305054)
			(end 0.12065 -0.2794)
			(stroke
				(width 0.1)
				(type default)
			)
			(layer "B.Fab")
		)
		(fp_line
			(start -0.120396 0.3048)
			(end -0.120396 0.2794)
			(stroke
				(width 0.1)
				(type default)
			)
			(layer "B.Fab")
		)
		(fp_line
			(start -0.120396 0.2794)
			(end 0.12065 0.2794)
			(stroke
				(width 0.1)
				(type default)
			)
			(layer "B.Fab")
		)
		(fp_line
			(start -0.12065 -0.2794)
			(end -0.12065 -0.3048)
			(stroke
				(width 0.1)
				(type default)
			)
			(layer "B.Fab")
		)
		(fp_line
			(start -0.12065 -0.3048)
			(end -0.67945 -0.3048)
			(stroke
				(width 0.1)
				(type default)
			)
			(layer "B.Fab")
		)
		(fp_line
			(start -0.67945 0.3048)
			(end -0.120396 0.3048)
			(stroke
				(width 0.1)
				(type default)
			)
			(layer "B.Fab")
		)
		(fp_line
			(start -0.67945 -0.3048)
			(end -0.67945 0.3048)
			(stroke
				(width 0.1)
				(type default)
			)
			(layer "B.Fab")
		)
		(pad "1" smd circle
			(at 0.40005 0)
			(size 0 0)
			(layers "B.Cu" "B.Mask" "B.Paste")
			(net "PVDD18_S5_P1")
		)
		(pad "2" smd circle
			(at -0.40005 0)
			(size 0 0)
			(layers "B.Cu" "B.Mask" "B.Paste")
			(net "GND")
		)
	)
	(footprint ""
		(layer "B.Cu")
		(at 428.98695 -36.007548 180)
		(property "Reference" "R1264"
			(at 0 0 0)
			(layer "B.SilkS")
			(hide yes)
			(effects
				(font
					(size 1.27 1.27)
				)
				(justify mirror)
			)
		)
		(property "Value" ""
			(at 0 0 0)
			(layer "B.Fab")
			(effects
				(font
					(size 1.27 1.27)
				)
				(justify mirror)
			)
		)
		(duplicate_pad_numbers_are_jumpers no)
		(fp_line
			(start 0.7874 0.4064)
			(end 0.7874 -0.4064)
			(stroke
				(width 0.1524)
				(type default)
			)
			(layer "B.SilkS")
		)
		(fp_line
			(start 0.7874 -0.4064)
			(end -0.7874 -0.4064)
			(stroke
				(width 0.1524)
				(type default)
			)
			(layer "B.SilkS")
		)
		(fp_line
			(start -0.7874 0.4064)
			(end 0.7874 0.4064)
			(stroke
				(width 0.1524)
				(type default)
			)
			(layer "B.SilkS")
		)
		(fp_line
			(start -0.7874 -0.4064)
			(end -0.7874 0.4064)
			(stroke
				(width 0.1524)
				(type default)
			)
			(layer "B.SilkS")
		)
		(fp_line
			(start 0.67945 0.3048)
			(end 0.67945 -0.305054)
			(stroke
				(width 0.1)
				(type default)
			)
			(layer "B.Fab")
		)
		(fp_line
			(start 0.67945 -0.305054)
			(end 0.12065 -0.305054)
			(stroke
				(width 0.1)
				(type default)
			)
			(layer "B.Fab")
		)
		(fp_line
			(start 0.12065 0.3048)
			(end 0.67945 0.3048)
			(stroke
				(width 0.1)
				(type default)
			)
			(layer "B.Fab")
		)
		(fp_line
			(start 0.12065 0.2794)
			(end 0.12065 0.3048)
			(stroke
				(width 0.1)
				(type default)
			)
			(layer "B.Fab")
		)
		(fp_line
			(start 0.12065 -0.2794)
			(end -0.12065 -0.2794)
			(stroke
				(width 0.1)
				(type default)
			)
			(layer "B.Fab")
		)
		(fp_line
			(start 0.12065 -0.305054)
			(end 0.12065 -0.2794)
			(stroke
				(width 0.1)
				(type default)
			)
			(layer "B.Fab")
		)
		(fp_line
			(start -0.120396 0.3048)
			(end -0.120396 0.2794)
			(stroke
				(width 0.1)
				(type default)
			)
			(layer "B.Fab")
		)
		(fp_line
			(start -0.120396 0.2794)
			(end 0.12065 0.2794)
			(stroke
				(width 0.1)
				(type default)
			)
			(layer "B.Fab")
		)
		(fp_line
			(start -0.12065 -0.2794)
			(end -0.12065 -0.3048)
			(stroke
				(width 0.1)
				(type default)
			)
			(layer "B.Fab")
		)
		(fp_line
			(start -0.12065 -0.3048)
			(end -0.67945 -0.3048)
			(stroke
				(width 0.1)
				(type default)
			)
			(layer "B.Fab")
		)
		(fp_line
			(start -0.67945 0.3048)
			(end -0.120396 0.3048)
			(stroke
				(width 0.1)
				(type default)
			)
			(layer "B.Fab")
		)
		(fp_line
			(start -0.67945 -0.3048)
			(end -0.67945 0.3048)
			(stroke
				(width 0.1)
				(type default)
			)
			(layer "B.Fab")
		)
		(pad "1" smd circle
			(at 0.40005 0)
			(size 0 0)
			(layers "B.Cu" "B.Mask" "B.Paste")
			(net "P1V8_AUX")
		)
		(pad "2" smd circle
			(at -0.40005 0)
			(size 0 0)
			(layers "B.Cu" "B.Mask" "B.Paste")
			(net "BIOS_DEBUG_MODE")
		)
	)
)
